FILE_TYPE = CONNECTIVITY;
{Allegro Design Entry HDL 16.6-p007 (v16-6-112F) 10/10/2012}
"PAGE_NUMBER" = 113;
0"NC";
1"GND\g";
2"GND\g";
3"GND\g";
4"GND\g";
5"GND\g";
6"P3V3_STBY\g";
7"P3V3_STBY\g";
8"P1V8_MCP_CPU0\g";
9"GND\g";
10"GND\g";
11"GND\g";
12"P1V8_MCP_CPU0\g";
13"P1V8_MCP_CPU1\g";
14"P1V8_MCP_CPU0\g";
15"P1V8_MCP_CPU0\g";
16"GND\g";
17"GND\g";
18"GND\g";
19"P3V3_STBY\g";
20"GND\g";
21"GND\g";
22"GND\g";
23"P3V3_STBY\g";
24"FM_CPU1_PKGID1";
25"JTAG_MCP_CPU1_TDI";
26"JTAG_MCP_TRST_N";
27"JTAG_MCP_TMS";
28"JTAG_MCP_MUX_TDO";
29"JTAG_MCP_MUX_TDI";
30"JTAG_MCP_TCK_R";
31"FM_CPU0_OR_CPU1_MCP_PRES";
32"JTAG_MCP_TCK";
33"JTAG_MCP_TRST_N";
34"JTAG_MCP_CPU0_TDI_R";
35"JTAG_MCP_CPU0_TDI";
36"JTAG_MCP_TMS";
37"JTAG_MCP_TMS_R1";
38"JTAG_MCP_CPU1_TDI_R";
39"FM_CPU0_OR_CPU1_MCP_PRES";
40"FM_CPU0_PKGID1";
41"TP_JTAG_MCP_IO8_RSVD";
42"JTAG_MCP_TRST_N";
43"JTAG_MCP_MUX_TDO";
44"JTAG_MCP_TMS_R";
45"JTAG_MCP_MUX_TDI";
46"PWRGD_CPU0_G_R";
47"JTAG_MCP_TCK_R";
48"PWRGD_CPU0_G";
49"JTAG_MCP_TCK";
50"JTAG_MCP_TMS";
51"FM_CPU1_CD_PRES";
52"JTAG_MCP_CPU1_TDO";
53"JTAG_MCP_CPU0_TDO";
54"FM_CPU0_CD_PRES";
55"JTAG_MCP_CPU1_TDI";
56"JTAG_MCP_CPU0_TDI";
57"JTAG_MCP_CPU1_TDI";
58"FM_CPU0_AND_CPU1_MCP_PRES";
59"JTAG_MCP_CPU0_TDO";
60"JTAG_MCP_MUX_TDO";
61"JTAG_MCP_MUX_TDI";
%"NC7SB3157"
"1","(-2075,3525)","2","mstr_analog","I107";
;
CDS_SEC"1"
CDS_LOCATION"U1M2"
BOM_COST"DEBUG"
SEC_TYPE"SMLF"
SEC"1"
ROOM"DEBUG"
CDS_LIB"mstr_analog"
LOCATION"U1M2"
MATERIAL"IC"
PACK_TYPE"SMLF"
PART_NUMBER"C99406-001";
"GND"
$PN"2"1;
"A"
$PN"4"60;
"VCC"
$PN"5"6;
"B1"
$PN"1"53;
"B0"
$PN"3"52;
"S"
$PN"6"51;
%"GND"
"1","(-2500,3225)","0","mstr_symbols","I109";
;
HDL_POWER"GND"
BODY_TYPE"PLUMBING"
SIZE"1B"
VOLTAGE"0.0V"
CDS_LIB"mstr_symbols";
"A\NAC"1;
%"GND"
"1","(-1150,4100)","0","mstr_symbols","I110";
;
HDL_POWER"GND"
CDS_LIB"mstr_symbols"
VOLTAGE"0.0V"
SIZE"1B"
BODY_TYPE"PLUMBING";
"A\NAC"2;
%"CAP_A"
"1","(-1550,3025)","2","dev_discrete","I116";
;
CDS_LOCATION"C1M31"
SEC_TYPE"0402V"
SEC"1"
ROOM"DEBUG"
BOM_COST"DEBUG"
CDS_SEC"1"
CDS_LIB"dev_discrete"
VALUE"0.01UF"
LOCATION"C1M31"
MATERIAL"X7R"
VOLTAGE"25V"
TOLERANCE"10%"
PACK_TYPE"0402V"
PART_NUMBER"A36096-045";
"B"
$PN"2"3;
"A"
$PN"1"6;
%"CAP_A"
"1","(-1250,3025)","2","dev_discrete","I117";
;
CDS_LOCATION"C1M32"
BOM_COST"DEBUG"
CDS_SEC"1"
SEC_TYPE"0402V"
SEC"1"
ROOM"DEBUG"
CDS_LIB"dev_discrete"
LOCATION"C1M32"
VALUE"1.0UF"
TOLERANCE"10%"
PACK_TYPE"0402V"
VOLTAGE"6.3V"
MATERIAL"X6S"
PART_NUMBER"D97712-004";
"B"
$PN"2"3;
"A"
$PN"1"6;
%"GND"
"1","(-1250,2725)","0","mstr_symbols","I118";
;
HDL_POWER"GND"
CDS_LIB"mstr_symbols"
SIZE"1B"
BODY_TYPE"PLUMBING"
VOLTAGE"0.0V"
ROOM"DEBUG"
BOM_COST"DEBUG";
"A\NAC"3;
%"CAP_A"
"1","(-2250,1250)","2","dev_discrete","I119";
;
CDS_LOCATION"C1M28"
SEC_TYPE"0402V"
SEC"1"
BOM_COST"DEBUG"
CDS_SEC"1"
ROOM"DEBUG"
CDS_LIB"dev_discrete"
LOCATION"C1M28"
VALUE"0.01UF"
TOLERANCE"10%"
PACK_TYPE"0402V"
VOLTAGE"25V"
MATERIAL"X7R"
PART_NUMBER"A36096-045";
"B"
$PN"2"4;
"A"
$PN"1"7;
%"GND"
"1","(-2250,1050)","0","mstr_symbols","I121";
;
HDL_POWER"GND"
CDS_LIB"mstr_symbols"
BOM_COST"DEBUG"
ROOM"DEBUG"
SIZE"1B"
VOLTAGE"0.0V"
BODY_TYPE"PLUMBING";
"A\NAC"4;
%"74CBTLV1G125"
"1","(-1500,850)","0","mstr_ttl","I127";
;
CDS_SEC"1"
CDS_LOCATION"U1M6"
BOM_COST"DEBUG"
SEC_TYPE"SMLF"
SEC"1"
ROOM"DEBUG"
CDS_LIB"mstr_ttl"
MATERIAL"IC"
PACK_TYPE"SMLF"
POWER_GROUP"VCC=P3V3_STBY;GND=GND;"
PART_NUMBER"C88177-001"
LOCATION"U1M6";
"OE_N \B"
$PN"1"58;
"B"
$PN"4"57;
"A"
$PN"2"59;
%"RES"
"2","(2450,3200)","2","mstr_discrete","I134";
;
CDS_SEC"1"
CDS_LOCATION"R4R6"
ROOM"DEBUG"
SEC"1"
SEC_TYPE"0402"
CDS_LIB"mstr_discrete"
TOLERANCE"1%"
LOCATION"R4R6"
PART_NUMBER"G21796-047"
VALUE"49.9"
MATERIAL"CHIP"
WATTAGE"1/16W"
PACK_TYPE"0402";
"A"
$PN"1"34;
"B"
$PN"2"35;
%"GND"
"1","(-975,4450)","0","mstr_symbols","I146";
;
HDL_POWER"GND"
CDS_LIB"mstr_symbols"
BODY_TYPE"PLUMBING"
SIZE"1B"
VOLTAGE"0.0V"
BOM_COST"DEBUG"
ROOM"DEBUG";
"A\NAC"5;
%"CAP_A"
"1","(-975,4650)","0","dev_discrete","I147";
;
CDS_LOCATION"C1M29"
ROOM"DEBUG"
CDS_SEC"1"
$SEC"1"
CDS_LIB"dev_discrete"
LOCATION"C1M29"
VALUE"0.1UF"
VOLTAGE"16V"
TOLERANCE"10%"
PART_NUMBER"A36096-030"
PACK_TYPE"0402V"
MATERIAL"X7R";
"B"
$PN"2"5;
"A"
$PN"1"8;
%"P3V3_STBY"
"1","(-1250,3300)","0","mstr_symbols","I160";
;
CDS_LIB"mstr_symbols"
SIZE"1B"
VOLTAGE"3.3V"
BODY_TYPE"PLUMBING"
HDL_POWER"P3V3_STBY";
"G\NAC"6;
%"P3V3_STBY"
"1","(-2250,1450)","0","mstr_symbols","I161";
;
SIZE"1B"
CDS_LIB"mstr_symbols"
VOLTAGE"3.3V"
BODY_TYPE"PLUMBING"
HDL_POWER"P3V3_STBY";
"G\NAC"7;
%"RES"
"1","(-2600,4150)","0","mstr_discrete","I168";
;
CDS_SEC"1"
CDS_LOCATION"R9B14"
ROOM"DEBUG"
SEC_TYPE"0402"
SEC"1"
CDS_LIB"mstr_discrete"
MATERIAL"CHIP"
LOCATION"R9B14"
WATTAGE"1/16W"
TOLERANCE"1%"
VALUE"1.00K"
PART_NUMBER"G21796-026"
PACK_TYPE"0402";
"B"
$PN"2"46;
"A"
$PN"1"48;
%"VCC_CORE"
"1","(-1100,4900)","0","mstr_symbols","I171";
;
CDS_LIB"mstr_symbols"
HDL_POWER"P1V8_MCP_CPU0";
"A"8;
%"SCONN10_C12536004"
"1","(-1375,4375)","0","mstr_sconn","I175";
;
CDS_SEC"1"
CDS_LOCATION"J9B4"
CDS_LIB"mstr_sconn"
PACK_TYPE"SMLF"
SEC_TYPE"SMLF"
SEC"1"
ROOM"DEBUG"
LOCATION"J9B4"
MATERIAL"CONN"
PART_NUMBER"C12536-004";
"IO1"
$PN"1"47;
"IO10"
$PN"10"2;
"IO3"
$PN"3"43;
"IO5"
$PN"5"44;
"IO7"
$PN"7"46;
"IO9"
$PN"9"45;
"IO2"
$PN"2"2;
"IO4"
$PN"4"8;
"IO6"
$PN"6"42;
"IO8"
$PN"8"41;
%"RES"
"2","(2600,4150)","2","mstr_discrete","I179";
;
CDS_SEC"1"
CDS_LOCATION"R9B9"
CDS_LIB"mstr_discrete"
SEC_TYPE"0402"
SEC"1"
WATTAGE"1/16W"
LOCATION"R9B9"
VALUE"1.00K"
TOLERANCE"1%"
MATERIAL"CHIP"
PART_NUMBER"G21796-026"
PACK_TYPE"0402";
"A"
$PN"1"32;
"B"
$PN"2"9;
%"RES"
"1","(2800,4400)","0","mstr_discrete","I180";
;
CDS_SEC"1"
CDS_LOCATION"R9B10"
BOM_COST"DEBUG"
SEC_TYPE"0402"
SEC"1"
ROOM"DEBUG"
CDS_LIB"mstr_discrete"
PACK_TYPE"0402"
LOCATION"R9B10"
PART_NUMBER"G21796-047"
TOLERANCE"1%"
MATERIAL"CHIP"
VALUE"49.9"
WATTAGE"1/16W";
"B"
$PN"2"30;
"A"
$PN"1"32;
%"GND"
"1","(2600,3950)","0","mstr_symbols","I182";
;
HDL_POWER"GND"
CDS_LIB"mstr_symbols"
SIZE"1B"
VOLTAGE"0.0V"
BODY_TYPE"PLUMBING";
"A\NAC"9;
%"74CBTLV1G125"
"1","(3575,4400)","0","mstr_ttl","I185";
;
CDS_SEC"1"
CDS_LOCATION"U9A5"
SEC"1"
BOM_COST"DEBUG"
SEC_TYPE"SMLF"
ROOM"DEBUG"
CDS_LIB"mstr_ttl"
POWER_GROUP"VCC=P3V3_STBY;GND=GND;"
PART_NUMBER"C88177-001"
MATERIAL"IC"
PACK_TYPE"SMLF"
LOCATION"U9A5";
"OE_N \B"
$PN"1"31;
"B"
$PN"4"10;
"A"
$PN"2"30;
%"GND"
"1","(3925,4250)","0","mstr_symbols","I186";
;
HDL_POWER"GND"
BODY_TYPE"PLUMBING"
SIZE"1B"
CDS_LIB"mstr_symbols"
VOLTAGE"0.0V";
"A\NAC"10;
%"RES"
"2","(2450,2075)","2","mstr_discrete","I188";
;
CDS_SEC"1"
SEC_TYPE"0402"
SEC"1"
CDS_LIB"mstr_discrete"
ROOM"DEBUG"
CDS_LOCATION"R6M8"
TOLERANCE"1%"
PACK_TYPE"0402"
LOCATION"R6M8"
VALUE"49.9"
WATTAGE"1/16W"
PART_NUMBER"G21796-047"
MATERIAL"CHIP";
"A"
$PN"1"38;
"B"
$PN"2"25;
%"74CBTLV1G125"
"1","(1600,2250)","0","mstr_ttl","I190";
;
CDS_SEC"1"
CDS_LOCATION"U6M1"
CDS_LIB"mstr_ttl"
ROOM"DEBUG"
BOM_COST"DEBUG"
SEC"1"
SEC_TYPE"SMLF"
POWER_GROUP"VCC=P3V3_STBY;GND=GND;"
LOCATION"U6M1"
PART_NUMBER"C88177-001"
PACK_TYPE"SMLF"
MATERIAL"IC";
"OE_N \B"
$PN"1"24;
"B"
$PN"4"38;
"A"
$PN"2"13;
%"RES"
"2","(2450,2650)","2","mstr_discrete","I195";
;
CDS_SEC"1"
CDS_LOCATION"R1M22"
SEC_TYPE"0402"
SEC"1"
ROOM"DEBUG"
CDS_LIB"mstr_discrete"
TOLERANCE"1%"
LOCATION"R1M22"
VALUE"49.9"
MATERIAL"CHIP"
WATTAGE"1/16W"
PART_NUMBER"G21796-047"
PACK_TYPE"0402";
"A"
$PN"1"37;
"B"
$PN"2"36;
%"74CBTLV1G125"
"1","(1600,2825)","0","mstr_ttl","I196";
;
CDS_SEC"1"
CDS_LOCATION"U1M5"
ROOM"DEBUG"
SEC"1"
BOM_COST"DEBUG"
SEC_TYPE"SMLF"
CDS_LIB"mstr_ttl"
POWER_GROUP"VCC=P3V3_STBY;GND=GND;"
LOCATION"U1M5"
PART_NUMBER"C88177-001"
PACK_TYPE"SMLF"
MATERIAL"IC";
"OE_N \B"
$PN"1"39;
"B"
$PN"4"37;
"A"
$PN"2"15;
%"RES"
"2","(1400,4225)","0","mstr_discrete","I199";
;
CDS_SEC"1"
CDS_LOCATION"R1M23"
BOM_COST"DEBUG"
SEC_TYPE"0402"
SEC"1"
ROOM"DEBUG"
CDS_LIB"mstr_discrete"
MATERIAL"EMPTY"
LOCATION"R1M23"
PART_NUMBER"G21796-026"
VALUE"1.00K"
WATTAGE"1/16W"
TOLERANCE"1%"
PACK_TYPE"0402";
"A"
$PN"1"33;
"B"
$PN"2"11;
%"GND"
"1","(1400,3950)","0","mstr_symbols","I200";
;
HDL_POWER"GND"
SIZE"1B"
VOLTAGE"0.0V"
CDS_LIB"mstr_symbols"
BODY_TYPE"PLUMBING";
"A\NAC"11;
%"VCC_CORE"
"1","(3575,1275)","0","mstr_symbols","I201";
;
CDS_LIB"mstr_symbols"
HDL_POWER"P1V8_MCP_CPU0";
"A"12;
%"RES"
"2","(3175,1025)","0","mstr_discrete","I202";
;
CDS_SEC"1"
CDS_LOCATION"R1M19"
CDS_LIB"mstr_discrete"
ROOM"DEBUG"
SEC_TYPE"0402"
BOM_COST"DEBUG"
SEC"1"
PACK_TYPE"0402"
MATERIAL"CHIP"
PART_NUMBER"G21796-026"
WATTAGE"1/16W"
TOLERANCE"1%"
VALUE"1.00K"
LOCATION"R1M19";
"A"
$PN"1"12;
"B"
$PN"2"27;
%"RES"
"2","(3425,1025)","0","mstr_discrete","I203";
;
CDS_SEC"1"
CDS_LOCATION"R9B12"
CDS_LIB"mstr_discrete"
BOM_COST"DEBUG"
SEC_TYPE"0402"
SEC"1"
ROOM"DEBUG"
LOCATION"R9B12"
MATERIAL"CHIP"
PACK_TYPE"0402"
PART_NUMBER"G21796-026"
WATTAGE"1/16W"
TOLERANCE"1%"
VALUE"1.00K";
"A"
$PN"1"12;
"B"
$PN"2"28;
%"RES"
"2","(2925,1025)","0","mstr_discrete","I204";
;
CDS_SEC"1"
CDS_LOCATION"R1M20"
CDS_LIB"mstr_discrete"
BOM_COST"DEBUG"
SEC_TYPE"0402"
SEC"1"
ROOM"DEBUG"
WATTAGE"1/16W"
MATERIAL"CHIP"
PACK_TYPE"0402"
TOLERANCE"1%"
VALUE"1.00K"
PART_NUMBER"G21796-026"
LOCATION"R1M20";
"A"
$PN"1"12;
"B"
$PN"2"29;
%"RES"
"2","(3675,1025)","0","mstr_discrete","I205";
;
CDS_SEC"1"
CDS_LOCATION"R1M21"
CDS_LIB"mstr_discrete"
ROOM"DEBUG"
SEC"1"
SEC_TYPE"0402"
BOM_COST"DEBUG"
LOCATION"R1M21"
PACK_TYPE"0402"
MATERIAL"CHIP"
WATTAGE"1/16W"
TOLERANCE"1%"
VALUE"1.00K"
PART_NUMBER"G21796-026";
"A"
$PN"1"12;
"B"
$PN"2"26;
%"74CBTLV1G125"
"1","(1625,3375)","0","mstr_ttl","I206";
;
CDS_SEC"1"
CDS_LOCATION"U4R1"
CDS_LIB"mstr_ttl"
ROOM"DEBUG"
SEC"1"
BOM_COST"DEBUG"
SEC_TYPE"SMLF"
POWER_GROUP"VCC=P3V3_STBY;GND=GND;"
LOCATION"U4R1"
PART_NUMBER"C88177-001"
PACK_TYPE"SMLF"
MATERIAL"IC";
"OE_N \B"
$PN"1"40;
"B"
$PN"4"34;
"A"
$PN"2"14;
%"VCC_CORE"
"1","(1275,2500)","0","mstr_symbols","I236";
;
VOLTAGE"1.8"
CDS_LIB"mstr_symbols"
HDL_POWER"P1V8_MCP_CPU1";
"A"13;
%"RES"
"1","(-2600,4625)","0","mstr_discrete","I239";
;
CDS_SEC"1"
CDS_LOCATION"R9B11"
SEC_TYPE"0402"
CDS_LIB"mstr_discrete"
SEC"1"
MATERIAL"CHIP"
LOCATION"R9B11"
PART_NUMBER"G21497-005"
WATTAGE"1/16W"
PACK_TYPE"0402"
TOLERANCE"5%"
VALUE"0.0";
"B"
$PN"2"47;
"A"
$PN"1"49;
%"RES"
"1","(-2600,4375)","0","mstr_discrete","I240";
;
CDS_SEC"1"
CDS_LOCATION"R9B13"
SEC_TYPE"0402"
SEC"1"
CDS_LIB"mstr_discrete"
MATERIAL"CHIP"
PART_NUMBER"G21497-005"
LOCATION"R9B13"
WATTAGE"1/16W"
PACK_TYPE"0402"
TOLERANCE"5%"
VALUE"0.0";
"B"
$PN"2"44;
"A"
$PN"1"50;
%"VCC_CORE"
"1","(1275,3675)","0","mstr_symbols","I241";
;
CDS_LIB"mstr_symbols"
HDL_POWER"P1V8_MCP_CPU0";
"A"14;
%"VCC_CORE"
"1","(1275,3075)","0","mstr_symbols","I245";
;
CDS_LIB"mstr_symbols"
HDL_POWER"P1V8_MCP_CPU0";
"A"15;
%"CAP_A"
"1","(2125,3200)","2","dev_discrete","I246";
;
CDS_LOCATION"C4R2"
SEC"1"
SEC_TYPE"0402V"
CDS_SEC"1"
ROOM"DEBUG"
CDS_LIB"dev_discrete"
LOCATION"C4R2"
PART_NUMBER"A36096-030"
VALUE"0.1UF"
TOLERANCE"10%"
PACK_TYPE"0402V"
VOLTAGE"16V"
MATERIAL"X7R";
"B"
$PN"2"16;
"A"
$PN"1"34;
%"GND"
"1","(2125,3000)","0","mstr_symbols","I247";
;
HDL_POWER"GND"
SIZE"1B"
VOLTAGE"0.0V"
CDS_LIB"mstr_symbols"
BODY_TYPE"PLUMBING";
"A\NAC"16;
%"CAP_A"
"1","(2125,2650)","2","dev_discrete","I248";
;
CDS_LOCATION"C1M33"
SEC"1"
SEC_TYPE"0402V"
BOM_COST"DEBUG"
ROOM"DEBUG"
CDS_SEC"1"
CDS_LIB"dev_discrete"
LOCATION"C1M33"
PART_NUMBER"A36096-030"
VALUE"0.1UF"
TOLERANCE"10%"
PACK_TYPE"0402V"
VOLTAGE"16V"
MATERIAL"X7R";
"B"
$PN"2"17;
"A"
$PN"1"37;
%"GND"
"1","(2125,2450)","0","mstr_symbols","I249";
;
HDL_POWER"GND"
SIZE"1B"
BODY_TYPE"PLUMBING"
CDS_LIB"mstr_symbols"
VOLTAGE"0.0V"
BOM_COST"DEBUG"
ROOM"DEBUG";
"A\NAC"17;
%"CAP_A"
"1","(2150,2075)","2","dev_discrete","I250";
;
CDS_LOCATION"C6M6"
SEC_TYPE"0402V"
ROOM"DEBUG"
BOM_COST"DEBUG"
CDS_SEC"1"
SEC"1"
CDS_LIB"dev_discrete"
LOCATION"C6M6"
PART_NUMBER"A36096-030"
VALUE"0.1UF"
TOLERANCE"10%"
PACK_TYPE"0402V"
VOLTAGE"16V"
MATERIAL"X7R";
"B"
$PN"2"18;
"A"
$PN"1"38;
%"GND"
"1","(2150,1850)","0","mstr_symbols","I251";
;
SIZE"1B"
HDL_POWER"GND"
CDS_LIB"mstr_symbols"
VOLTAGE"0.0V"
BODY_TYPE"PLUMBING"
BOM_COST"DEBUG"
ROOM"DEBUG";
"A\NAC"18;
%"NC7SB3157"
"1","(-2125,2325)","2","mstr_analog","I255";
;
CDS_SEC"1"
CDS_LOCATION"U2M1"
ROOM"DEBUG"
SEC"1"
SEC_TYPE"SMLF"
BOM_COST"DEBUG"
CDS_LIB"mstr_analog"
LOCATION"U2M1"
MATERIAL"IC"
PART_NUMBER"C99406-001"
PACK_TYPE"SMLF";
"GND"
$PN"2"21;
"A"
$PN"4"61;
"VCC"
$PN"5"19;
"B1"
$PN"1"56;
"B0"
$PN"3"55;
"S"
$PN"6"54;
%"P3V3_STBY"
"1","(-1275,2100)","0","mstr_symbols","I259";
;
CDS_LIB"mstr_symbols"
SIZE"1B"
VOLTAGE"3.3V"
BODY_TYPE"PLUMBING"
HDL_POWER"P3V3_STBY";
"G\NAC"19;
%"GND"
"1","(-1275,1500)","0","mstr_symbols","I261";
;
HDL_POWER"GND"
CDS_LIB"mstr_symbols"
VOLTAGE"0.0V"
SIZE"1B"
BODY_TYPE"PLUMBING"
BOM_COST"DEBUG"
ROOM"DEBUG";
"A\NAC"20;
%"GND"
"1","(-2550,2025)","0","mstr_symbols","I263";
;
HDL_POWER"GND"
CDS_LIB"mstr_symbols"
SIZE"1B"
VOLTAGE"0.0V"
BODY_TYPE"PLUMBING";
"A\NAC"21;
%"CAP_A"
"1","(-1275,1825)","2","dev_discrete","I265";
;
CDS_LOCATION"C1M34"
SEC_TYPE"0402V"
SEC"1"
CDS_LIB"dev_discrete"
ROOM"DEBUG"
CDS_SEC"1"
BOM_COST"DEBUG"
VALUE"0.01UF"
LOCATION"C1M34"
PACK_TYPE"0402V"
TOLERANCE"10%"
MATERIAL"X7R"
VOLTAGE"25V"
PART_NUMBER"A36096-045";
"B"
$PN"2"20;
"A"
$PN"1"19;
%"CAP_A"
"1","(-1600,1825)","2","dev_discrete","I266";
;
CDS_LOCATION"C1M35"
SEC_TYPE"0402V"
SEC"1"
ROOM"DEBUG"
CDS_SEC"1"
BOM_COST"DEBUG"
CDS_LIB"dev_discrete"
VOLTAGE"25V"
TOLERANCE"10%"
MATERIAL"X7R"
PACK_TYPE"0402V"
LOCATION"C1M35"
PART_NUMBER"A36096-045"
VALUE"0.01UF";
"B"
$PN"2"20;
"A"
$PN"1"19;
%"CAP_A"
"1","(3025,3650)","2","dev_discrete","I267";
;
CDS_LOCATION"C1L20"
CDS_LIB"dev_discrete"
ROOM"DEBUG"
CDS_SEC"1"
BOM_COST"DEBUG"
SEC"1"
SEC_TYPE"0402V"
MATERIAL"X7R"
VOLTAGE"25V"
PACK_TYPE"0402V"
TOLERANCE"10%"
VALUE"0.01UF"
PART_NUMBER"A36096-045"
LOCATION"C1L20";
"B"
$PN"2"22;
"A"
$PN"1"23;
%"GND"
"1","(3025,3450)","0","mstr_symbols","I268";
;
ROOM"DEBUG"
BOM_COST"DEBUG"
VOLTAGE"0.0V"
CDS_LIB"mstr_symbols"
BODY_TYPE"PLUMBING"
SIZE"1B"
HDL_POWER"GND";
"A\NAC"22;
%"P3V3_STBY"
"1","(3025,3850)","0","mstr_symbols","I269";
;
HDL_POWER"P3V3_STBY"
BODY_TYPE"PLUMBING"
VOLTAGE"3.3V"
CDS_LIB"mstr_symbols"
SIZE"1B";
"G\NAC"23;
END.
